(kicad_pcb
	(version 20260206)
	(generator "pcbnew")
	(generator_version "10.0")
	(general
		(thickness 1.6)
		(legacy_teardrops no)
	)
	(paper "A4")
	(title_block
		(title "Wiwynn_Tioga_Pass_MB.brd")
		(comment 1 "Tioga Pass / footprint 1357 of 4770 (J1C1), pads 73-76 of 76")
	)
	(layers
		(0 "F.Cu" signal "TOP")
		(4 "In1.Cu" signal "L2GND")
		(6 "In2.Cu" signal "L3")
		(8 "In3.Cu" signal "L4GND")
		(10 "In4.Cu" signal "L5")
		(12 "In5.Cu" signal "L6GND")
		(14 "In6.Cu" signal "L7VCC")
		(16 "In7.Cu" signal "L8VCC")
		(18 "In8.Cu" signal "L9GND")
		(20 "In9.Cu" signal "L10")
		(22 "In10.Cu" signal "L11GND")
		(24 "In11.Cu" signal "L12")
		(26 "In12.Cu" signal "L13GND")
		(2 "B.Cu" signal "BOTTOM")
		(9 "F.Adhes" user "F.Adhesive")
		(11 "B.Adhes" user "B.Adhesive")
		(13 "F.Paste" user "Package Geometry/Pastemask Top")
		(15 "B.Paste" user "Package Geometry/Pastemask Bottom")
		(5 "F.SilkS" user "Ref Des/Silkscreen Top")
		(7 "B.SilkS" user "Ref Des/Silkscreen Bottom")
		(1 "F.Mask" user "Board Geometry/Soldermask Top")
		(3 "B.Mask" user "Board Geometry/Soldermask Bottom")
		(17 "Dwgs.User" user "User.Drawings")
		(19 "Cmts.User" user "User.Comments")
		(21 "Eco1.User" user "User.Eco1")
		(23 "Eco2.User" user "User.Eco2")
		(25 "Edge.Cuts" user "Board Geometry/Outline")
		(27 "Margin" user)
		(31 "F.CrtYd" user "Package Geometry/Place Bound Top")
		(29 "B.CrtYd" user "Package Geometry/Place Bound Bottom")
		(35 "F.Fab" user "Ref Des/Assembly Top")
		(33 "B.Fab" user "Ref Des/Assembly Bottom")
	)
	(footprint ""
		(layer "F.Cu")
		(at 2.29997 -97.769934 -90)
		(property "Reference" "J1C1"
			(at 0 0 270)
			(layer "F.SilkS")
			(hide yes)
			(effects
				(font
					(size 1.27 1.27)
				)
			)
		)
		(property "Value" "*"
			(at -20.8026 -3.4036 270)
			(unlocked yes)
			(layer "F.Fab")
			(hide yes)
			(effects
				(font
					(size 1.27 1.016)
					(thickness 0.1524)
				)
			)
		)
		(property "Device Type" "DM-FCI-CONN76-8R-GP-U-01_CONN-A"
			(at -20.8026 -4.9276 270)
			(unlocked yes)
			(layer "F.Fab")
			(hide yes)
			(effects
				(font
					(size 1.27 1.016)
					(thickness 0.1524)
				)
			)
		)
		(duplicate_pad_numbers_are_jumpers no)
		(pad "J2" thru_hole circle
			(at -4.99999 -6.299962 270)
			(size 0.8636 0.8636)
			(drill 0.499872)
			(layers "*.Cu" "*.Mask")
			(remove_unused_layers no)
			(net "GND")
			(clearance 0.1778)
			(thermal_gap 0.1778)
		)
		(pad "J4" thru_hole circle
			(at -0.999998 -6.299962 270)
			(size 0.8636 0.8636)
			(drill 0.499872)
			(layers "*.Cu" "*.Mask")
			(remove_unused_layers no)
			(net "GND")
			(clearance 0.1778)
			(thermal_gap 0.1778)
		)
		(pad "J6" thru_hole circle
			(at 2.999994 -6.299962 270)
			(size 0.8636 0.8636)
			(drill 0.499872)
			(layers "*.Cu" "*.Mask")
			(remove_unused_layers no)
			(net "GND")
			(clearance 0.1778)
			(thermal_gap 0.1778)
		)
		(pad "J8" thru_hole circle
			(at 6.999986 -6.299962 270)
			(size 0.8636 0.8636)
			(drill 0.499872)
			(layers "*.Cu" "*.Mask")
			(remove_unused_layers no)
			(net "GND")
			(clearance 0.1778)
			(thermal_gap 0.1778)
		)
	)
)
